(kicad_pcb
	(version 20260206)
	(generator "pcbnew")
	(generator_version "10.0")
	(general
		(thickness 1.6)
		(legacy_teardrops no)
	)
	(paper "A4")
	(title_block
		(title "Wiwynn_Tioga_Pass_MB.brd")
		(comment 1 "Tioga Pass / footprint 1899 of 4770 (J4G2), pads 244-291 of 291")
	)
	(layers
		(0 "F.Cu" signal "TOP")
		(4 "In1.Cu" signal "L2GND")
		(6 "In2.Cu" signal "L3")
		(8 "In3.Cu" signal "L4GND")
		(10 "In4.Cu" signal "L5")
		(12 "In5.Cu" signal "L6GND")
		(14 "In6.Cu" signal "L7VCC")
		(16 "In7.Cu" signal "L8VCC")
		(18 "In8.Cu" signal "L9GND")
		(20 "In9.Cu" signal "L10")
		(22 "In10.Cu" signal "L11GND")
		(24 "In11.Cu" signal "L12")
		(26 "In12.Cu" signal "L13GND")
		(2 "B.Cu" signal "BOTTOM")
		(9 "F.Adhes" user "F.Adhesive")
		(11 "B.Adhes" user "B.Adhesive")
		(13 "F.Paste" user "Package Geometry/Pastemask Top")
		(15 "B.Paste" user "Package Geometry/Pastemask Bottom")
		(5 "F.SilkS" user "Ref Des/Silkscreen Top")
		(7 "B.SilkS" user "Ref Des/Silkscreen Bottom")
		(1 "F.Mask" user "Board Geometry/Soldermask Top")
		(3 "B.Mask" user "Board Geometry/Soldermask Bottom")
		(17 "Dwgs.User" user "User.Drawings")
		(19 "Cmts.User" user "User.Comments")
		(21 "Eco1.User" user "User.Eco1")
		(23 "Eco2.User" user "User.Eco2")
		(25 "Edge.Cuts" user "Board Geometry/Outline")
		(27 "Margin" user)
		(31 "F.CrtYd" user "Package Geometry/Place Bound Top")
		(29 "B.CrtYd" user "Package Geometry/Place Bound Bottom")
		(35 "F.Fab" user "Ref Des/Assembly Top")
		(33 "B.Fab" user "Ref Des/Assembly Bottom")
	)
	(footprint ""
		(layer "F.Cu")
		(at 194.700398 -5.822442 90)
		(property "Reference" "J4G2"
			(at 6.596888 37.58311 0)
			(unlocked yes)
			(layer "F.SilkS")
			(effects
				(font
					(size 0.7874 0.5842)
					(thickness 0.1524)
				)
				(justify left)
			)
		)
		(property "Value" ""
			(at 0 0 90)
			(layer "F.Fab")
			(effects
				(font
					(size 1.27 1.27)
				)
			)
		)
		(duplicate_pad_numbers_are_jumpers no)
		(pad "241" smd rect
			(at 4.59994 86.700106 90)
			(size 1.8034 0.508)
			(layers "F.Cu" "F.Mask" "F.Paste")
			(net "GND")
		)
		(pad "242" smd rect
			(at 4.59994 87.54999 90)
			(size 1.8034 0.508)
			(layers "F.Cu" "F.Mask" "F.Paste")
			(net "M_B_DQ<32>")
		)
		(pad "243" smd rect
			(at 4.59994 88.399874 90)
			(size 1.8034 0.508)
			(layers "F.Cu" "F.Mask" "F.Paste")
			(net "GND")
		)
		(pad "244" smd rect
			(at 4.59994 89.250012 90)
			(size 1.8034 0.508)
			(layers "F.Cu" "F.Mask" "F.Paste")
			(net "M_B_DQS_DN<4>")
		)
		(pad "245" smd rect
			(at 4.59994 90.099896 90)
			(size 1.8034 0.508)
			(layers "F.Cu" "F.Mask" "F.Paste")
			(net "M_B_DQS_DP<4>")
		)
		(pad "246" smd rect
			(at 4.59994 90.950034 90)
			(size 1.8034 0.508)
			(layers "F.Cu" "F.Mask" "F.Paste")
			(net "GND")
		)
		(pad "247" smd rect
			(at 4.59994 91.799918 90)
			(size 1.8034 0.508)
			(layers "F.Cu" "F.Mask" "F.Paste")
			(net "M_B_DQ<38>")
		)
		(pad "248" smd rect
			(at 4.59994 92.650056 90)
			(size 1.8034 0.508)
			(layers "F.Cu" "F.Mask" "F.Paste")
			(net "GND")
		)
		(pad "249" smd rect
			(at 4.59994 93.49994 90)
			(size 1.8034 0.508)
			(layers "F.Cu" "F.Mask" "F.Paste")
			(net "M_B_DQ<34>")
		)
		(pad "250" smd rect
			(at 4.59994 94.350078 90)
			(size 1.8034 0.508)
			(layers "F.Cu" "F.Mask" "F.Paste")
			(net "GND")
		)
		(pad "251" smd rect
			(at 4.59994 95.199962 90)
			(size 1.8034 0.508)
			(layers "F.Cu" "F.Mask" "F.Paste")
			(net "M_B_DQ<44>")
		)
		(pad "252" smd rect
			(at 4.59994 96.0501 90)
			(size 1.8034 0.508)
			(layers "F.Cu" "F.Mask" "F.Paste")
			(net "GND")
		)
		(pad "253" smd rect
			(at 4.59994 96.899984 90)
			(size 1.8034 0.508)
			(layers "F.Cu" "F.Mask" "F.Paste")
			(net "M_B_DQ<40>")
		)
		(pad "254" smd rect
			(at 4.59994 97.750122 90)
			(size 1.8034 0.508)
			(layers "F.Cu" "F.Mask" "F.Paste")
			(net "GND")
		)
		(pad "255" smd rect
			(at 4.59994 98.600006 90)
			(size 1.8034 0.508)
			(layers "F.Cu" "F.Mask" "F.Paste")
			(net "M_B_DQS_DN<5>")
		)
		(pad "256" smd rect
			(at 4.59994 99.44989 90)
			(size 1.8034 0.508)
			(layers "F.Cu" "F.Mask" "F.Paste")
			(net "M_B_DQS_DP<5>")
		)
		(pad "257" smd rect
			(at 4.59994 100.300028 90)
			(size 1.8034 0.508)
			(layers "F.Cu" "F.Mask" "F.Paste")
			(net "GND")
		)
		(pad "258" smd rect
			(at 4.59994 101.149912 90)
			(size 1.8034 0.508)
			(layers "F.Cu" "F.Mask" "F.Paste")
			(net "M_B_DQ<46>")
		)
		(pad "259" smd rect
			(at 4.59994 102.00005 90)
			(size 1.8034 0.508)
			(layers "F.Cu" "F.Mask" "F.Paste")
			(net "GND")
		)
		(pad "260" smd rect
			(at 4.59994 102.849934 90)
			(size 1.8034 0.508)
			(layers "F.Cu" "F.Mask" "F.Paste")
			(net "M_B_DQ<42>")
		)
		(pad "261" smd rect
			(at 4.59994 103.700072 90)
			(size 1.8034 0.508)
			(layers "F.Cu" "F.Mask" "F.Paste")
			(net "GND")
		)
		(pad "262" smd rect
			(at 4.59994 104.549956 90)
			(size 1.8034 0.508)
			(layers "F.Cu" "F.Mask" "F.Paste")
			(net "M_B_DQ<52>")
		)
		(pad "263" smd rect
			(at 4.59994 105.400094 90)
			(size 1.8034 0.508)
			(layers "F.Cu" "F.Mask" "F.Paste")
			(net "GND")
		)
		(pad "264" smd rect
			(at 4.59994 106.249978 90)
			(size 1.8034 0.508)
			(layers "F.Cu" "F.Mask" "F.Paste")
			(net "M_B_DQ<48>")
		)
		(pad "265" smd rect
			(at 4.59994 107.100116 90)
			(size 1.8034 0.508)
			(layers "F.Cu" "F.Mask" "F.Paste")
			(net "GND")
		)
		(pad "266" smd rect
			(at 4.59994 107.95 90)
			(size 1.8034 0.508)
			(layers "F.Cu" "F.Mask" "F.Paste")
			(net "M_B_DQS_DN<6>")
		)
		(pad "267" smd rect
			(at 4.59994 108.799884 90)
			(size 1.8034 0.508)
			(layers "F.Cu" "F.Mask" "F.Paste")
			(net "M_B_DQS_DP<6>")
		)
		(pad "268" smd rect
			(at 4.59994 109.650022 90)
			(size 1.8034 0.508)
			(layers "F.Cu" "F.Mask" "F.Paste")
			(net "GND")
		)
		(pad "269" smd rect
			(at 4.59994 110.499906 90)
			(size 1.8034 0.508)
			(layers "F.Cu" "F.Mask" "F.Paste")
			(net "M_B_DQ<54>")
		)
		(pad "270" smd rect
			(at 4.59994 111.350044 90)
			(size 1.8034 0.508)
			(layers "F.Cu" "F.Mask" "F.Paste")
			(net "GND")
		)
		(pad "271" smd rect
			(at 4.59994 112.199928 90)
			(size 1.8034 0.508)
			(layers "F.Cu" "F.Mask" "F.Paste")
			(net "M_B_DQ<50>")
		)
		(pad "272" smd rect
			(at 4.59994 113.050066 90)
			(size 1.8034 0.508)
			(layers "F.Cu" "F.Mask" "F.Paste")
			(net "GND")
		)
		(pad "273" smd rect
			(at 4.59994 113.89995 90)
			(size 1.8034 0.508)
			(layers "F.Cu" "F.Mask" "F.Paste")
			(net "M_B_DQ<60>")
		)
		(pad "274" smd rect
			(at 4.59994 114.750088 90)
			(size 1.8034 0.508)
			(layers "F.Cu" "F.Mask" "F.Paste")
			(net "GND")
		)
		(pad "275" smd rect
			(at 4.59994 115.599972 90)
			(size 1.8034 0.508)
			(layers "F.Cu" "F.Mask" "F.Paste")
			(net "M_B_DQ<56>")
		)
		(pad "276" smd rect
			(at 4.59994 116.45011 90)
			(size 1.8034 0.508)
			(layers "F.Cu" "F.Mask" "F.Paste")
			(net "GND")
		)
		(pad "277" smd rect
			(at 4.59994 117.299994 90)
			(size 1.8034 0.508)
			(layers "F.Cu" "F.Mask" "F.Paste")
			(net "M_B_DQS_DN<7>")
		)
		(pad "278" smd rect
			(at 4.59994 118.149878 90)
			(size 1.8034 0.508)
			(layers "F.Cu" "F.Mask" "F.Paste")
			(net "M_B_DQS_DP<7>")
		)
		(pad "279" smd rect
			(at 4.59994 119.000016 90)
			(size 1.8034 0.508)
			(layers "F.Cu" "F.Mask" "F.Paste")
			(net "GND")
		)
		(pad "280" smd rect
			(at 4.59994 119.8499 90)
			(size 1.8034 0.508)
			(layers "F.Cu" "F.Mask" "F.Paste")
			(net "M_B_DQ<62>")
		)
		(pad "281" smd rect
			(at 4.59994 120.700038 90)
			(size 1.8034 0.508)
			(layers "F.Cu" "F.Mask" "F.Paste")
			(net "GND")
		)
		(pad "282" smd rect
			(at 4.59994 121.549922 90)
			(size 1.8034 0.508)
			(layers "F.Cu" "F.Mask" "F.Paste")
			(net "M_B_DQ<58>")
		)
		(pad "283" smd rect
			(at 4.59994 122.40006 90)
			(size 1.8034 0.508)
			(layers "F.Cu" "F.Mask" "F.Paste")
			(net "GND")
		)
		(pad "284" smd rect
			(at 4.59994 123.249944 90)
			(size 1.8034 0.508)
			(layers "F.Cu" "F.Mask" "F.Paste")
			(net "PVPP_ABC")
		)
		(pad "285" smd rect
			(at 4.59994 124.100082 90)
			(size 1.8034 0.508)
			(layers "F.Cu" "F.Mask" "F.Paste")
			(net "SMB_DDR_ABC_VPP_SDA")
		)
		(pad "286" smd rect
			(at 4.59994 124.949966 90)
			(size 1.8034 0.508)
			(layers "F.Cu" "F.Mask" "F.Paste")
			(net "PVPP_ABC")
		)
		(pad "287" smd rect
			(at 4.59994 125.800104 90)
			(size 1.8034 0.508)
			(layers "F.Cu" "F.Mask" "F.Paste")
			(net "PVPP_ABC")
		)
		(pad "288" smd rect
			(at 4.59994 126.649988 90)
			(size 1.8034 0.508)
			(layers "F.Cu" "F.Mask" "F.Paste")
			(net "PVPP_ABC")
		)
	)
)
